FILE_TYPE = MACRO_DRAWING;
SET COLOR_WIRE YELLOW;
SET COLOR_PROP ORANGE;
SET COLOR_DOT WHITE;
SET COLOR_ARC YELLOW;
SET COLOR_BODY GREEN;
SET COLOR_NOTE PURPLE;
SET PROP_DISPLAY VALUE;
SET PAGE_NUMBER P1;
FORCEADD SYNONYM..1
(1850 2050);
PAINT MONO (1850 2050);
FORCEPROP 2 LAST PATH 4P
J 0
(1850 2150);
DISPLAY 0.872340 (1850 2150);
PAINT YELLOW (1850 2150);
FORCEPROP 1 LAST NEEDS_NO_SIZE TRUE
J 0
(1875 2125);
DISPLAY 0.872340 (1875 2125);
PAINT MONO (1875 2125);
DISPLAY INVISIBLE (1875 2125);
FORCEPROP 1 LAST BODY_TYPE PLUMBING
J 0
(1850 2100);
DISPLAY 0.872340 (1850 2100);
PAINT GREEN (1850 2100);
DISPLAY INVISIBLE (1850 2100);
FORCEPROP 2 LAST CDS_LIB mstr_standard
J 0
(1850 2050);
DISPLAY 0.851064 (1850 2050);
DISPLAY INVISIBLE (1850 2050);
FORCEADD DRAWING..2
(1275 1750);
PAINT MONO (1275 1750);
FORCEPROP 1 LAST LAST_MODIFIED Tue Oct 25 13:21:17 2011
J 0
(1575 1500);
DISPLAY 0.872340 (1575 1500);
PAINT GREEN (1575 1500);
FORCEPROP 1 LAST TITLE P12V_STBY
J 0
(1325 1700);
DISPLAY 0.872340 (1325 1700);
PAINT GREEN (1325 1700);
FORCEPROP 1 LAST ABBREV P12V_STBY
J 0
(1325 1650);
DISPLAY 0.872340 (1325 1650);
PAINT GREEN (1325 1650);
WIRE 16 -1 (1800 2050)(1200 2050);
FORCEPROP 2 LAST SIG_NAME G\I
J 0
(1025 2060);
DISPLAY 0.872340 (1025 2060);
PAINT MONO (1025 2060);
WIRE 0 -1 (1900 2050)(2050 2050);
FORCEPROP 2 LAST SIG_NAME P12V_STBY \G
J 0
(2075 2085);
DISPLAY 0.872340 (2075 2085);
PAINT MONO (2075 2085);
QUIT
